(kicad_pcb
	(version 20260206)
	(generator "pcbnew")
	(generator_version "10.0")
	(general
		(thickness 1.6)
		(legacy_teardrops no)
	)
	(paper "A4")
	(title_block
		(title "04192023_DAF0TMB3IC0_F0TG_MB_C_brd_V02_OCP.brd")
		(comment 1 "Grand Teton / footprints 127-132 of 8354")
	)
	(layers
		(0 "F.Cu" signal "TOP")
		(4 "In1.Cu" signal "GND")
		(6 "In2.Cu" signal "IN1")
		(8 "In3.Cu" signal "GND1")
		(10 "In4.Cu" signal "IN2")
		(12 "In5.Cu" signal "GND2")
		(14 "In6.Cu" signal "IN3")
		(16 "In7.Cu" signal "GND3")
		(18 "In8.Cu" signal "VCC")
		(20 "In9.Cu" signal "VCC1")
		(22 "In10.Cu" signal "GND4")
		(24 "In11.Cu" signal "IN4")
		(26 "In12.Cu" signal "GND5")
		(28 "In13.Cu" signal "IN5")
		(30 "In14.Cu" signal "GND6")
		(32 "In15.Cu" signal "IN6")
		(34 "In16.Cu" signal "GND7")
		(2 "B.Cu" signal "BOTTOM")
		(9 "F.Adhes" user "F.Adhesive")
		(11 "B.Adhes" user "B.Adhesive")
		(13 "F.Paste" user "Package Geometry/Pastemask Top")
		(15 "B.Paste" user "Package Geometry/Pastemask Bottom")
		(5 "F.SilkS" user "Ref Des/Silkscreen Top")
		(7 "B.SilkS" user "Ref Des/Silkscreen Bottom")
		(1 "F.Mask" user "Board Geometry/Soldermask Top")
		(3 "B.Mask" user "Board Geometry/Soldermask Bottom")
		(17 "Dwgs.User" user "User.Drawings")
		(19 "Cmts.User" user "User.Comments")
		(21 "Eco1.User" user "User.Eco1")
		(23 "Eco2.User" user "User.Eco2")
		(25 "Edge.Cuts" user "Board Geometry/Outline")
		(27 "Margin" user)
		(31 "F.CrtYd" user "Package Geometry/Place Bound Top")
		(29 "B.CrtYd" user "Package Geometry/Place Bound Bottom")
		(35 "F.Fab" user "Ref Des/Assembly Top")
		(33 "B.Fab" user "Ref Des/Assembly Bottom")
	)
	(footprint ""
		(layer "F.Cu")
		(at 316.738 -358.267 180)
		(property "Reference" "R8064"
			(at 0 0 180)
			(layer "F.SilkS")
			(hide yes)
			(effects
				(font
					(size 1.27 1.27)
				)
			)
		)
		(property "Value" ""
			(at 0 0 180)
			(layer "F.Fab")
			(effects
				(font
					(size 1.27 1.27)
				)
			)
		)
		(duplicate_pad_numbers_are_jumpers no)
		(fp_line
			(start 0.7874 0.4064)
			(end -0.7874 0.4064)
			(stroke
				(width 0.1524)
				(type default)
			)
			(layer "F.SilkS")
		)
		(fp_line
			(start 0.7874 -0.4064)
			(end 0.7874 0.4064)
			(stroke
				(width 0.1524)
				(type default)
			)
			(layer "F.SilkS")
		)
		(fp_line
			(start -0.7874 0.4064)
			(end -0.7874 -0.4064)
			(stroke
				(width 0.1524)
				(type default)
			)
			(layer "F.SilkS")
		)
		(fp_line
			(start -0.7874 -0.4064)
			(end 0.7874 -0.4064)
			(stroke
				(width 0.1524)
				(type default)
			)
			(layer "F.SilkS")
		)
		(fp_line
			(start 0.67945 0.3048)
			(end 0.120396 0.3048)
			(stroke
				(width 0.1)
				(type default)
			)
			(layer "F.Fab")
		)
		(fp_line
			(start 0.67945 -0.3048)
			(end 0.67945 0.3048)
			(stroke
				(width 0.1)
				(type default)
			)
			(layer "F.Fab")
		)
		(fp_line
			(start 0.12065 -0.2794)
			(end 0.12065 -0.3048)
			(stroke
				(width 0.1)
				(type default)
			)
			(layer "F.Fab")
		)
		(fp_line
			(start 0.12065 -0.3048)
			(end 0.67945 -0.3048)
			(stroke
				(width 0.1)
				(type default)
			)
			(layer "F.Fab")
		)
		(fp_line
			(start 0.120396 0.3048)
			(end 0.120396 0.2794)
			(stroke
				(width 0.1)
				(type default)
			)
			(layer "F.Fab")
		)
		(fp_line
			(start 0.120396 0.2794)
			(end -0.12065 0.2794)
			(stroke
				(width 0.1)
				(type default)
			)
			(layer "F.Fab")
		)
		(fp_line
			(start -0.12065 0.3048)
			(end -0.67945 0.3048)
			(stroke
				(width 0.1)
				(type default)
			)
			(layer "F.Fab")
		)
		(fp_line
			(start -0.12065 0.2794)
			(end -0.12065 0.3048)
			(stroke
				(width 0.1)
				(type default)
			)
			(layer "F.Fab")
		)
		(fp_line
			(start -0.12065 -0.2794)
			(end 0.12065 -0.2794)
			(stroke
				(width 0.1)
				(type default)
			)
			(layer "F.Fab")
		)
		(fp_line
			(start -0.12065 -0.305054)
			(end -0.12065 -0.2794)
			(stroke
				(width 0.1)
				(type default)
			)
			(layer "F.Fab")
		)
		(fp_line
			(start -0.67945 0.3048)
			(end -0.67945 -0.305054)
			(stroke
				(width 0.1)
				(type default)
			)
			(layer "F.Fab")
		)
		(fp_line
			(start -0.67945 -0.305054)
			(end -0.12065 -0.305054)
			(stroke
				(width 0.1)
				(type default)
			)
			(layer "F.Fab")
		)
		(pad "1" smd circle
			(at -0.40005 0 180)
			(size 0 0)
			(layers "F.Cu" "F.Mask" "F.Paste")
			(net "PVDDCR_CPU1_P0_OCP_N")
		)
		(pad "2" smd circle
			(at 0.40005 0 180)
			(size 0 0)
			(layers "F.Cu" "F.Mask" "F.Paste")
			(net "PVDDCR_CPU1_P0_OCP_N_R")
		)
	)
	(footprint ""
		(layer "F.Cu")
		(at 328.367644 -138.893042 -90)
		(property "Reference" "PR434"
			(at 0 0 270)
			(layer "F.SilkS")
			(hide yes)
			(effects
				(font
					(size 1.27 1.27)
				)
			)
		)
		(property "Value" ""
			(at 0 0 270)
			(layer "F.Fab")
			(effects
				(font
					(size 1.27 1.27)
				)
			)
		)
		(duplicate_pad_numbers_are_jumpers no)
		(fp_line
			(start -0.7874 0.4064)
			(end -0.7874 -0.4064)
			(stroke
				(width 0.1524)
				(type default)
			)
			(layer "F.SilkS")
		)
		(fp_line
			(start 0.7874 0.4064)
			(end -0.7874 0.4064)
			(stroke
				(width 0.1524)
				(type default)
			)
			(layer "F.SilkS")
		)
		(fp_line
			(start -0.7874 -0.4064)
			(end 0.7874 -0.4064)
			(stroke
				(width 0.1524)
				(type default)
			)
			(layer "F.SilkS")
		)
		(fp_line
			(start 0.7874 -0.4064)
			(end 0.7874 0.4064)
			(stroke
				(width 0.1524)
				(type default)
			)
			(layer "F.SilkS")
		)
		(fp_line
			(start -0.67945 0.3048)
			(end -0.67945 -0.305054)
			(stroke
				(width 0.1)
				(type default)
			)
			(layer "F.Fab")
		)
		(fp_line
			(start -0.12065 0.3048)
			(end -0.67945 0.3048)
			(stroke
				(width 0.1)
				(type default)
			)
			(layer "F.Fab")
		)
		(fp_line
			(start 0.120396 0.3048)
			(end 0.120396 0.2794)
			(stroke
				(width 0.1)
				(type default)
			)
			(layer "F.Fab")
		)
		(fp_line
			(start 0.67945 0.3048)
			(end 0.120396 0.3048)
			(stroke
				(width 0.1)
				(type default)
			)
			(layer "F.Fab")
		)
		(fp_line
			(start -0.12065 0.2794)
			(end -0.12065 0.3048)
			(stroke
				(width 0.1)
				(type default)
			)
			(layer "F.Fab")
		)
		(fp_line
			(start 0.120396 0.2794)
			(end -0.12065 0.2794)
			(stroke
				(width 0.1)
				(type default)
			)
			(layer "F.Fab")
		)
		(fp_line
			(start -0.12065 -0.2794)
			(end 0.12065 -0.2794)
			(stroke
				(width 0.1)
				(type default)
			)
			(layer "F.Fab")
		)
		(fp_line
			(start 0.12065 -0.2794)
			(end 0.12065 -0.3048)
			(stroke
				(width 0.1)
				(type default)
			)
			(layer "F.Fab")
		)
		(fp_line
			(start 0.12065 -0.3048)
			(end 0.67945 -0.3048)
			(stroke
				(width 0.1)
				(type default)
			)
			(layer "F.Fab")
		)
		(fp_line
			(start 0.67945 -0.3048)
			(end 0.67945 0.3048)
			(stroke
				(width 0.1)
				(type default)
			)
			(layer "F.Fab")
		)
		(fp_line
			(start -0.67945 -0.305054)
			(end -0.12065 -0.305054)
			(stroke
				(width 0.1)
				(type default)
			)
			(layer "F.Fab")
		)
		(fp_line
			(start -0.12065 -0.305054)
			(end -0.12065 -0.2794)
			(stroke
				(width 0.1)
				(type default)
			)
			(layer "F.Fab")
		)
		(pad "1" smd circle
			(at -0.40005 0 270)
			(size 0 0)
			(layers "F.Cu" "F.Mask" "F.Paste")
			(net "PVDD18_S5_P0_FB_RC")
		)
		(pad "2" smd circle
			(at 0.40005 0 270)
			(size 0 0)
			(layers "F.Cu" "F.Mask" "F.Paste")
			(net "VSENSE_PVDD18_S5_P0_DP")
		)
	)
	(footprint ""
		(layer "F.Cu")
		(at 458.346302 -407.877264)
		(property "Reference" "PC6582_2"
			(at 0 0 0)
			(layer "F.SilkS")
			(hide yes)
			(effects
				(font
					(size 1.27 1.27)
				)
			)
		)
		(property "Value" ""
			(at 0 0 0)
			(layer "F.Fab")
			(effects
				(font
					(size 1.27 1.27)
				)
			)
		)
		(duplicate_pad_numbers_are_jumpers no)
		(fp_line
			(start -1.524 -0.762)
			(end 1.524 -0.762)
			(stroke
				(width 0.1524)
				(type default)
			)
			(layer "F.SilkS")
		)
		(fp_line
			(start -1.524 0.762)
			(end -1.524 -0.762)
			(stroke
				(width 0.1524)
				(type default)
			)
			(layer "F.SilkS")
		)
		(fp_line
			(start 1.524 -0.762)
			(end 1.524 0.762)
			(stroke
				(width 0.1524)
				(type default)
			)
			(layer "F.SilkS")
		)
		(fp_line
			(start 1.524 0.762)
			(end -1.524 0.762)
			(stroke
				(width 0.1524)
				(type default)
			)
			(layer "F.SilkS")
		)
		(fp_line
			(start -1.1049 -0.724916)
			(end -1.1049 0.724916)
			(stroke
				(width 0.1)
				(type default)
			)
			(layer "F.Fab")
		)
		(fp_line
			(start -1.1049 0.724916)
			(end 1.1049 0.724916)
			(stroke
				(width 0.1)
				(type default)
			)
			(layer "F.Fab")
		)
		(fp_line
			(start 1.1049 -0.724916)
			(end -1.1049 -0.724916)
			(stroke
				(width 0.1)
				(type default)
			)
			(layer "F.Fab")
		)
		(fp_line
			(start 1.1049 0.724916)
			(end 1.1049 -0.724916)
			(stroke
				(width 0.1)
				(type default)
			)
			(layer "F.Fab")
		)
		(pad "1" smd rect
			(at -0.889 0 180)
			(size 1.016 1.27)
			(layers "F.Cu" "F.Mask" "F.Paste")
			(net "SW_P12V_AUX_P0V9_RETIMER_CPU0_FLT")
		)
		(pad "2" smd rect
			(at 0.889 0 180)
			(size 1.016 1.27)
			(layers "F.Cu" "F.Mask" "F.Paste")
			(net "GND")
		)
	)
	(footprint ""
		(layer "F.Cu")
		(at 7.899908 -51.999896)
		(property "Reference" "J7"
			(at -1.016 -3.495548 0)
			(unlocked yes)
			(layer "F.SilkS")
			(effects
				(font
					(size 0.7874 0.5842)
					(thickness 0.1524)
				)
			)
		)
		(property "Value" ""
			(at 0 0 0)
			(layer "F.Fab")
			(effects
				(font
					(size 1.27 1.27)
				)
			)
		)
		(duplicate_pad_numbers_are_jumpers no)
		(fp_line
			(start -1.700022 -2.739898)
			(end 1.700022 -2.739898)
			(stroke
				(width 0.1524)
				(type default)
			)
			(layer "F.SilkS")
		)
		(fp_line
			(start -1.700022 -2.4257)
			(end -1.700022 -2.739898)
			(stroke
				(width 0.1524)
				(type default)
			)
			(layer "F.SilkS")
		)
		(fp_line
			(start -1.700022 -1.1557)
			(end -1.700022 -1.3843)
			(stroke
				(width 0.1524)
				(type default)
			)
			(layer "F.SilkS")
		)
		(fp_line
			(start -1.700022 0.1143)
			(end -1.700022 -0.1143)
			(stroke
				(width 0.1524)
				(type default)
			)
			(layer "F.SilkS")
		)
		(fp_line
			(start -1.700022 1.3843)
			(end -1.700022 1.1557)
			(stroke
				(width 0.1524)
				(type default)
			)
			(layer "F.SilkS")
		)
		(fp_line
			(start -1.700022 2.739898)
			(end -1.700022 2.4257)
			(stroke
				(width 0.1524)
				(type default)
			)
			(layer "F.SilkS")
		)
		(fp_line
			(start 1.700022 -2.739898)
			(end 1.700022 -2.4257)
			(stroke
				(width 0.1524)
				(type default)
			)
			(layer "F.SilkS")
		)
		(fp_line
			(start 1.700022 -1.3843)
			(end 1.700022 -1.1557)
			(stroke
				(width 0.1524)
				(type default)
			)
			(layer "F.SilkS")
		)
		(fp_line
			(start 1.700022 -0.1143)
			(end 1.700022 0.1143)
			(stroke
				(width 0.1524)
				(type default)
			)
			(layer "F.SilkS")
		)
		(fp_line
			(start 1.700022 1.1557)
			(end 1.700022 1.3843)
			(stroke
				(width 0.1524)
				(type default)
			)
			(layer "F.SilkS")
		)
		(fp_line
			(start 1.700022 2.4257)
			(end 1.700022 2.739898)
			(stroke
				(width 0.1524)
				(type default)
			)
			(layer "F.SilkS")
		)
		(fp_line
			(start 1.700022 2.739898)
			(end -1.700022 2.739898)
			(stroke
				(width 0.1524)
				(type default)
			)
			(layer "F.SilkS")
		)
		(fp_poly
			(pts
				(xy -3.383534 -1.905) (xy -4.399534 -1.397) (xy -4.399534 -2.413)
			)
			(stroke
				(width 0)
				(type default)
			)
			(fill yes)
			(layer "F.SilkS")
		)
		(fp_line
			(start -1.700022 -2.739898)
			(end 1.700022 -2.739898)
			(stroke
				(width 0.1)
				(type default)
			)
			(layer "F.Fab")
		)
		(fp_line
			(start -1.700022 2.739898)
			(end -1.700022 -2.739898)
			(stroke
				(width 0.1)
				(type default)
			)
			(layer "F.Fab")
		)
		(fp_line
			(start 1.700022 -2.739898)
			(end 1.700022 2.739898)
			(stroke
				(width 0.1)
				(type default)
			)
			(layer "F.Fab")
		)
		(fp_line
			(start 1.700022 2.739898)
			(end -1.700022 2.739898)
			(stroke
				(width 0.1)
				(type default)
			)
			(layer "F.Fab")
		)
		(fp_poly
			(pts
				(xy -4.399534 -2.413) (xy -4.399534 -1.397) (xy -3.383534 -1.905)
			)
			(stroke
				(width 0)
				(type default)
			)
			(fill yes)
			(layer "F.Fab")
		)
		(pad "1" smd rect
			(at -2.050034 -1.905 270)
			(size 0.762 2.413)
			(layers "F.Cu" "F.Mask" "F.Paste")
			(net "CPU1_XTRIG_R1_L4")
		)
		(pad "2" smd rect
			(at 2.050034 -1.905 270)
			(size 0.762 2.413)
			(layers "F.Cu" "F.Mask" "F.Paste")
			(net "GND")
		)
		(pad "3" smd rect
			(at -2.050034 -0.635 270)
			(size 0.762 2.413)
			(layers "F.Cu" "F.Mask" "F.Paste")
			(net "CPU1_XTRIG_R1_L5")
		)
		(pad "4" smd rect
			(at 2.050034 -0.635 270)
			(size 0.762 2.413)
			(layers "F.Cu" "F.Mask" "F.Paste")
			(net "GND")
		)
		(pad "5" smd rect
			(at -2.050034 0.635 270)
			(size 0.762 2.413)
			(layers "F.Cu" "F.Mask" "F.Paste")
			(net "CPU1_XTRIG_R1_L6")
		)
		(pad "6" smd rect
			(at 2.050034 0.635 270)
			(size 0.762 2.413)
			(layers "F.Cu" "F.Mask" "F.Paste")
			(net "GND")
		)
		(pad "7" smd rect
			(at -2.050034 1.905 270)
			(size 0.762 2.413)
			(layers "F.Cu" "F.Mask" "F.Paste")
			(net "CPU1_XTRIG_R1_L7")
		)
		(pad "8" smd rect
			(at 2.050034 1.905 270)
			(size 0.762 2.413)
			(layers "F.Cu" "F.Mask" "F.Paste")
			(net "GND")
		)
	)
	(footprint ""
		(layer "F.Cu")
		(at 79.315564 -408.517344 -90)
		(property "Reference" "C6649"
			(at 0 0 270)
			(layer "F.SilkS")
			(hide yes)
			(effects
				(font
					(size 1.27 1.27)
				)
			)
		)
		(property "Value" ""
			(at 0 0 270)
			(layer "F.Fab")
			(effects
				(font
					(size 1.27 1.27)
				)
			)
		)
		(duplicate_pad_numbers_are_jumpers no)
		(fp_line
			(start -0.299974 0.150114)
			(end -0.299974 -0.150114)
			(stroke
				(width 0.1)
				(type default)
			)
			(layer "F.Fab")
		)
		(fp_line
			(start 0.299974 0.150114)
			(end -0.299974 0.150114)
			(stroke
				(width 0.1)
				(type default)
			)
			(layer "F.Fab")
		)
		(fp_line
			(start -0.299974 -0.150114)
			(end 0.299974 -0.150114)
			(stroke
				(width 0.1)
				(type default)
			)
			(layer "F.Fab")
		)
		(fp_line
			(start 0.299974 -0.150114)
			(end 0.299974 0.150114)
			(stroke
				(width 0.1)
				(type default)
			)
			(layer "F.Fab")
		)
		(pad "1" smd rect
			(at -0.2667 0 270)
			(size 0.3048 0.381)
			(layers "F.Cu" "F.Mask" "F.Paste")
			(net "P5E_CPU1_P0_TX_BUF_C_DP<10>")
		)
		(pad "2" smd rect
			(at 0.2667 0 270)
			(size 0.3048 0.381)
			(layers "F.Cu" "F.Mask" "F.Paste")
			(net "P5E_CPU1_P0_TX_BUF_DP<10>")
		)
	)
	(footprint ""
		(layer "F.Cu")
		(at 253.97841 -45.865542 90)
		(property "Reference" "PR3970"
			(at 0 0 90)
			(layer "F.SilkS")
			(hide yes)
			(effects
				(font
					(size 1.27 1.27)
				)
			)
		)
		(property "Value" ""
			(at 0 0 90)
			(layer "F.Fab")
			(effects
				(font
					(size 1.27 1.27)
				)
			)
		)
		(duplicate_pad_numbers_are_jumpers no)
		(fp_line
			(start 0.7874 -0.4064)
			(end 0.7874 0.4064)
			(stroke
				(width 0.1524)
				(type default)
			)
			(layer "F.SilkS")
		)
		(fp_line
			(start -0.7874 -0.4064)
			(end 0.7874 -0.4064)
			(stroke
				(width 0.1524)
				(type default)
			)
			(layer "F.SilkS")
		)
		(fp_line
			(start 0.7874 0.4064)
			(end -0.7874 0.4064)
			(stroke
				(width 0.1524)
				(type default)
			)
			(layer "F.SilkS")
		)
		(fp_line
			(start -0.7874 0.4064)
			(end -0.7874 -0.4064)
			(stroke
				(width 0.1524)
				(type default)
			)
			(layer "F.SilkS")
		)
		(fp_line
			(start -0.12065 -0.305054)
			(end -0.12065 -0.2794)
			(stroke
				(width 0.1)
				(type default)
			)
			(layer "F.Fab")
		)
		(fp_line
			(start -0.67945 -0.305054)
			(end -0.12065 -0.305054)
			(stroke
				(width 0.1)
				(type default)
			)
			(layer "F.Fab")
		)
		(fp_line
			(start 0.67945 -0.3048)
			(end 0.67945 0.3048)
			(stroke
				(width 0.1)
				(type default)
			)
			(layer "F.Fab")
		)
		(fp_line
			(start 0.12065 -0.3048)
			(end 0.67945 -0.3048)
			(stroke
				(width 0.1)
				(type default)
			)
			(layer "F.Fab")
		)
		(fp_line
			(start 0.12065 -0.2794)
			(end 0.12065 -0.3048)
			(stroke
				(width 0.1)
				(type default)
			)
			(layer "F.Fab")
		)
		(fp_line
			(start -0.12065 -0.2794)
			(end 0.12065 -0.2794)
			(stroke
				(width 0.1)
				(type default)
			)
			(layer "F.Fab")
		)
		(fp_line
			(start 0.120396 0.2794)
			(end -0.12065 0.2794)
			(stroke
				(width 0.1)
				(type default)
			)
			(layer "F.Fab")
		)
		(fp_line
			(start -0.12065 0.2794)
			(end -0.12065 0.3048)
			(stroke
				(width 0.1)
				(type default)
			)
			(layer "F.Fab")
		)
		(fp_line
			(start 0.67945 0.3048)
			(end 0.120396 0.3048)
			(stroke
				(width 0.1)
				(type default)
			)
			(layer "F.Fab")
		)
		(fp_line
			(start 0.120396 0.3048)
			(end 0.120396 0.2794)
			(stroke
				(width 0.1)
				(type default)
			)
			(layer "F.Fab")
		)
		(fp_line
			(start -0.12065 0.3048)
			(end -0.67945 0.3048)
			(stroke
				(width 0.1)
				(type default)
			)
			(layer "F.Fab")
		)
		(fp_line
			(start -0.67945 0.3048)
			(end -0.67945 -0.305054)
			(stroke
				(width 0.1)
				(type default)
			)
			(layer "F.Fab")
		)
		(pad "1" smd circle
			(at -0.40005 0 90)
			(size 0 0)
			(layers "F.Cu" "F.Mask" "F.Paste")
			(net "P12V_E1S_SENSE_0")
		)
		(pad "2" smd circle
			(at 0.40005 0 90)
			(size 0 0)
			(layers "F.Cu" "F.Mask" "F.Paste")
			(net "GND")
		)
	)
)
